# BASEBOARD_FAB2 (Tioga Pass) — schematic netlist excerpt (pin names and nets, part order shuffled) for the footprints in the layout excerpt that follows; sources: Cadence DE-HDL packaged netlist, KiCad conversion of Wiwynn_Tioga_Pass_MB.brd

R1T6  RES  2.7K 1% CHIP  pkg 0402  page 164 : A = P3V3_STBY ; B = FM_BOARD_REV_ID1
R8E30  2K15R2F-1-GP  1%  pkg SMD-RG1  page 142 : \1\ = P3V3_STBY ; \2\ = FM_ALL_WAKE_N

(kicad_pcb
	(version 20260206)
	(generator "pcbnew")
	(generator_version "10.0")
	(general
		(thickness 1.6)
		(legacy_teardrops no)
	)
	(paper "A4")
	(title_block
		(title "Wiwynn_Tioga_Pass_MB.brd")
		(comment 1 "Tioga Pass / footprints 2992-2993 of 4770")
	)
	(layers
		(0 "F.Cu" signal "TOP")
		(4 "In1.Cu" signal "L2GND")
		(6 "In2.Cu" signal "L3")
		(8 "In3.Cu" signal "L4GND")
		(10 "In4.Cu" signal "L5")
		(12 "In5.Cu" signal "L6GND")
		(14 "In6.Cu" signal "L7VCC")
		(16 "In7.Cu" signal "L8VCC")
		(18 "In8.Cu" signal "L9GND")
		(20 "In9.Cu" signal "L10")
		(22 "In10.Cu" signal "L11GND")
		(24 "In11.Cu" signal "L12")
		(26 "In12.Cu" signal "L13GND")
		(2 "B.Cu" signal "BOTTOM")
		(9 "F.Adhes" user "F.Adhesive")
		(11 "B.Adhes" user "B.Adhesive")
		(13 "F.Paste" user "Package Geometry/Pastemask Top")
		(15 "B.Paste" user "Package Geometry/Pastemask Bottom")
		(5 "F.SilkS" user "Ref Des/Silkscreen Top")
		(7 "B.SilkS" user "Ref Des/Silkscreen Bottom")
		(1 "F.Mask" user "Board Geometry/Soldermask Top")
		(3 "B.Mask" user "Board Geometry/Soldermask Bottom")
		(17 "Dwgs.User" user "User.Drawings")
		(19 "Cmts.User" user "User.Comments")
		(21 "Eco1.User" user "User.Eco1")
		(23 "Eco2.User" user "User.Eco2")
		(25 "Edge.Cuts" user "Board Geometry/Outline")
		(27 "Margin" user)
		(31 "F.CrtYd" user "Package Geometry/Place Bound Top")
		(29 "B.CrtYd" user "Package Geometry/Place Bound Bottom")
		(35 "F.Fab" user "Ref Des/Assembly Top")
		(33 "B.Fab" user "Ref Des/Assembly Bottom")
	)
	(footprint ""
		(layer "B.Cu")
		(at 409.067 -48.768)
		(property "Reference" "R1T6"
			(at 0 0 0)
			(layer "B.SilkS")
			(hide yes)
			(effects
				(font
					(size 1.27 1.27)
				)
				(justify mirror)
			)
		)
		(property "Value" ""
			(at 0 0 0)
			(layer "B.Fab")
			(effects
				(font
					(size 1.27 1.27)
				)
				(justify mirror)
			)
		)
		(duplicate_pad_numbers_are_jumpers no)
		(fp_poly
			(pts
				(xy 0.2794 -0.1016) (xy -0.2794 -0.1016) (xy -0.2794 0.9906) (xy 0.2794 0.9906)
			)
			(stroke
				(width 0)
				(type default)
			)
			(fill no)
			(layer "B.CrtYd")
		)
		(fp_line
			(start -0.2794 -0.1016)
			(end 0.2794 -0.1016)
			(stroke
				(width 0.1)
				(type default)
			)
			(layer "B.Fab")
		)
		(fp_line
			(start -0.2794 0.9906)
			(end -0.2794 -0.1016)
			(stroke
				(width 0.1)
				(type default)
			)
			(layer "B.Fab")
		)
		(fp_line
			(start 0.2794 -0.1016)
			(end 0.2794 0.9906)
			(stroke
				(width 0.1)
				(type default)
			)
			(layer "B.Fab")
		)
		(fp_line
			(start 0.2794 0.9906)
			(end -0.2794 0.9906)
			(stroke
				(width 0.1)
				(type default)
			)
			(layer "B.Fab")
		)
		(pad "1" smd rect
			(at 0 0 180)
			(size 0.508 0.508)
			(layers "B.Cu" "B.Mask" "B.Paste")
			(net "P3V3_STBY")
		)
		(pad "2" smd rect
			(at 0 0.889 180)
			(size 0.508 0.508)
			(layers "B.Cu" "B.Mask" "B.Paste")
			(net "FM_BOARD_REV_ID1")
		)
	)
	(footprint ""
		(layer "B.Cu")
		(at 480.1108 -57.1754 90)
		(property "Reference" "R8E30"
			(at 0 0 90)
			(layer "B.SilkS")
			(hide yes)
			(effects
				(font
					(size 1.27 1.27)
				)
				(justify mirror)
			)
		)
		(property "Value" "*"
			(at -0.064008 -4.108196 90)
			(unlocked yes)
			(layer "B.Fab")
			(hide yes)
			(effects
				(font
					(size 1.27 1.016)
					(thickness 0.1524)
				)
				(justify mirror)
			)
		)
		(property "Device Type" "2K15R2F-1-GP_SMD-RG1-2K15R2F-1A"
			(at -0.064008 -5.632196 90)
			(unlocked yes)
			(layer "B.Fab")
			(hide yes)
			(effects
				(font
					(size 1.27 1.016)
					(thickness 0.1524)
				)
				(justify mirror)
			)
		)
		(duplicate_pad_numbers_are_jumpers no)
		(fp_line
			(start 0.508 -0.9398)
			(end 0.508 0.9398)
			(stroke
				(width 0.1524)
				(type default)
			)
			(layer "B.SilkS")
		)
		(fp_line
			(start -0.508 -0.9398)
			(end 0.508 -0.9398)
			(stroke
				(width 0.1524)
				(type default)
			)
			(layer "B.SilkS")
		)
		(fp_rect
			(start 0.508 0.9398)
			(end -0.508 -0.9398)
			(stroke
				(width 0)
				(type default)
			)
			(fill no)
			(layer "B.CrtYd")
		)
		(fp_rect
			(start 0.508 0.9398)
			(end -0.508 -0.9398)
			(stroke
				(width 0)
				(type default)
			)
			(fill no)
			(layer "B.Fab")
		)
		(pad "1" smd custom
			(at 0 -0.4445 270)
			(size 0.1397 0.1397)
			(layers "B.Cu" "B.Mask" "B.Paste")
			(net "P3V3_STBY")
			(options
				(clearance outline)
				(anchor circle)
			)
			(primitives
				(gr_poly
					(pts
						(arc
							(start -0.1778 0.2794)
							(mid -0.249642 0.249642)
							(end -0.2794 0.1778)
						)
						(arc
							(start -0.2794 -0.1778)
							(mid -0.249642 -0.249642)
							(end -0.1778 -0.2794)
						)
						(arc
							(start 0.1778 -0.2794)
							(mid 0.249642 -0.249642)
							(end 0.2794 -0.1778)
						)
						(arc
							(start 0.2794 0.1778)
							(mid 0.249642 0.249642)
							(end 0.1778 0.2794)
						)
					)
					(width 0)
					(fill yes)
				)
			)
		)
		(pad "2" smd custom
			(at 0 0.4445 270)
			(size 0.1397 0.1397)
			(layers "B.Cu" "B.Mask" "B.Paste")
			(net "FM_ALL_WAKE_N")
			(options
				(clearance outline)
				(anchor circle)
			)
			(primitives
				(gr_poly
					(pts
						(arc
							(start -0.1778 0.2794)
							(mid -0.249642 0.249642)
							(end -0.2794 0.1778)
						)
						(arc
							(start -0.2794 -0.1778)
							(mid -0.249642 -0.249642)
							(end -0.1778 -0.2794)
						)
						(arc
							(start 0.1778 -0.2794)
							(mid 0.249642 -0.249642)
							(end 0.2794 -0.1778)
						)
						(arc
							(start 0.2794 0.1778)
							(mid 0.249642 0.249642)
							(end 0.1778 0.2794)
						)
					)
					(width 0)
					(fill yes)
				)
			)
		)
	)
)
